(kicad_pcb
	(version 20221018)
	(generator pcbnew)
	(general
    (thickness 1.562)
  )
	(paper "A4")
	(title_block
    (title "Thunderbolt PCIe Adaper")
    (date "2024-07-09")
    (rev "1.0.3")
    (comment 1 "www.antmicro.com")
    (comment 2 "Antmicro Ltd.")
		(comment 9 "footprint 58 of 271 (U3), pads 94-96 of 96")
	)
	(layers
    (0 "F.Cu" signal)
    (1 "In1.Cu" signal)
    (2 "In2.Cu" signal)
    (3 "In3.Cu" signal)
    (4 "In4.Cu" signal)
    (31 "B.Cu" signal)
    (32 "B.Adhes" user "B.Adhesive")
    (33 "F.Adhes" user "F.Adhesive")
    (34 "B.Paste" user)
    (35 "F.Paste" user)
    (36 "B.SilkS" user "B.Silkscreen")
    (37 "F.SilkS" user "F.Silkscreen")
    (38 "B.Mask" user)
    (39 "F.Mask" user)
    (40 "Dwgs.User" user "User.Drawings")
    (41 "Cmts.User" user "User.Comments")
    (42 "Eco1.User" user "User.Eco1")
    (43 "Eco2.User" user "User.Eco2")
    (44 "Edge.Cuts" user)
    (45 "Margin" user)
    (46 "B.CrtYd" user "B.Courtyard")
    (47 "F.CrtYd" user "F.Courtyard")
    (48 "B.Fab" user)
    (49 "F.Fab" user)
  )
	(footprint "antmicro-footprints:IC_TPS65983BAZBHR"
    (layer "F.Cu")
    (at 156.89 62.85)
    (property "Author" "Antmicro")
    (property "License" "Apache-2.0")
    (property "MPN" "TPS65983BAZBHR")
    (property "Manufacturer" "Texas Instruments")
    (property "Sheetfile" "power.kicad_sch")
    (property "Sheetname" "Power")
    (property "ki_description" "USB Interface IC Universal USB Type-C and Power Delivery (PD) 3.0 controller 96-NFBGA -10°C to 85")
    (property "ki_keywords" "IC")
    (attr smd)
    (fp_text reference "U3" (at 0 -3.8 unlocked) (layer "F.SilkS")
        (effects (font (size 0.7 0.7) (thickness 0.15)))
    )
    (fp_text value "TPS65983BAZBHR" (at 0 4.1 unlocked) (layer "F.Fab")
        (effects (font (size 0.7 0.7) (thickness 0.15)))
    )
    (pad "L9" smd oval (at 1.5 2.5) (size 0.17 0.25) (layers "F.Cu" "F.Paste" "F.Mask")
      (net 11 "CC1") (pinfunction "C_CC1") (pintype "bidirectional"))
    (pad "L10" smd oval (at 2 2.5) (size 0.17 0.25) (layers "F.Cu" "F.Paste" "F.Mask")
      (net 10 "CC2") (pinfunction "C_CC2") (pintype "bidirectional"))
    (pad "L11" smd circle (at 2.5 2.5) (size 0.25 0.25) (layers "F.Cu" "F.Paste" "F.Mask")
      (net 219 "unconnected-(U3-NC-PadL11)") (pinfunction "NC") (pintype "no_connect") (solder_paste_margin_ratio -1))
  )
)
